(kicad_pcb
	(version 20260206)
	(generator "pcbnew")
	(generator_version "10.0")
	(general
		(thickness 1.6)
		(legacy_teardrops no)
	)
	(paper "A4")
	(title_block
		(title "timecard-production-celestica-r4006 — R4006-B0001-02_R01.brd")
		(comment 1 "Time Appliance Project (Time Card) / footprints 658-664 of 1113")
	)
	(layers
		(0 "F.Cu" signal "TOP")
		(4 "In1.Cu" signal "L02_GND1")
		(6 "In2.Cu" signal "L03_SIG1")
		(8 "In3.Cu" signal "L04_GND2")
		(10 "In4.Cu" signal "L05_VCC1")
		(12 "In5.Cu" signal "L06_VCC2")
		(14 "In6.Cu" signal "L07_GND3")
		(16 "In7.Cu" signal "L08_SIG2")
		(18 "In8.Cu" signal "L09_GND4")
		(2 "B.Cu" signal "BOTTOM")
		(9 "F.Adhes" user "F.Adhesive")
		(11 "B.Adhes" user "B.Adhesive")
		(13 "F.Paste" user "Package Geometry/Pastemask Top")
		(15 "B.Paste" user "Package Geometry/Pastemask Bottom")
		(5 "F.SilkS" user "Ref Des/Silkscreen Top")
		(7 "B.SilkS" user "Ref Des/Silkscreen Bottom")
		(1 "F.Mask" user "Board Geometry/Soldermask Top")
		(3 "B.Mask" user "Board Geometry/Soldermask Bottom")
		(17 "Dwgs.User" user "User.Drawings")
		(19 "Cmts.User" user "User.Comments")
		(21 "Eco1.User" user "User.Eco1")
		(23 "Eco2.User" user "User.Eco2")
		(25 "Edge.Cuts" user "Board Geometry/Outline")
		(27 "Margin" user)
		(31 "F.CrtYd" user "Package Geometry/Place Bound Top")
		(29 "B.CrtYd" user "Package Geometry/Place Bound Bottom")
		(35 "F.Fab" user "Ref Des/Assembly Top")
		(33 "B.Fab" user "Ref Des/Assembly Bottom")
	)
	(footprint ""
		(layer "F.Cu")
		(at 138.43 -16.129 180)
		(property "Reference" "C234"
			(at 2.032 -1.56337 0)
			(unlocked yes)
			(layer "F.SilkS")
			(effects
				(font
					(size 0.7874 0.5842)
					(thickness 0.1524)
				)
			)
		)
		(property "Value" "VAL*"
			(at 0.193548 2.13614 180)
			(unlocked yes)
			(layer "F.Fab")
			(hide yes)
			(effects
				(font
					(size 0.7874 0.5842)
					(thickness 0.1524)
				)
			)
		)
		(property "User Part Number" "PARTNUM*"
			(at 0.216154 4.185666 180)
			(unlocked yes)
			(layer "Cmts.User")
			(hide yes)
			(effects
				(font
					(size 0.7874 0.5842)
					(thickness 0.1524)
				)
			)
		)
		(property "Device Type" "CAPACITOR-G104-0B103-EK,0.01UFA"
			(at 0.184404 1.180592 180)
			(unlocked yes)
			(layer "F.Fab")
			(hide yes)
			(effects
				(font
					(size 0.7874 0.5842)
					(thickness 0.1524)
				)
			)
		)
		(property "Tolerance" "TOL*"
			(at 0.216154 3.1496 180)
			(unlocked yes)
			(layer "Cmts.User")
			(hide yes)
			(effects
				(font
					(size 0.7874 0.5842)
					(thickness 0.1524)
				)
			)
		)
		(duplicate_pad_numbers_are_jumpers no)
		(fp_line
			(start 0.671322 0.4445)
			(end -0.671322 0.4445)
			(stroke
				(width 0.1)
				(type default)
			)
			(layer "F.SilkS")
		)
		(fp_line
			(start 0.671322 -0.4445)
			(end 0.671322 0.4445)
			(stroke
				(width 0.1)
				(type default)
			)
			(layer "F.SilkS")
		)
		(fp_line
			(start -0.671322 0.4445)
			(end -0.671322 -0.4445)
			(stroke
				(width 0.1)
				(type default)
			)
			(layer "F.SilkS")
		)
		(fp_line
			(start -0.671322 -0.4445)
			(end 0.671322 -0.4445)
			(stroke
				(width 0.1)
				(type default)
			)
			(layer "F.SilkS")
		)
		(fp_rect
			(start -0.671322 -0.4445)
			(end 0.671322 0.4445)
			(stroke
				(width 0)
				(type default)
			)
			(fill no)
			(layer "F.CrtYd")
		)
		(fp_line
			(start 0.31496 0.1651)
			(end 0.31496 -0.1651)
			(stroke
				(width 0.1)
				(type default)
			)
			(layer "F.Fab")
		)
		(fp_line
			(start 0.31496 -0.1651)
			(end -0.31496 -0.1651)
			(stroke
				(width 0.1)
				(type default)
			)
			(layer "F.Fab")
		)
		(fp_line
			(start -0.31496 0.1651)
			(end 0.31496 0.1651)
			(stroke
				(width 0.1)
				(type default)
			)
			(layer "F.Fab")
		)
		(fp_line
			(start -0.31496 -0.1651)
			(end -0.31496 0.1651)
			(stroke
				(width 0.1)
				(type default)
			)
			(layer "F.Fab")
		)
		(pad "1" smd rect
			(at -0.264922 0 180)
			(size 0.3048 0.381)
			(layers "F.Cu" "F.Mask" "F.Paste")
			(net "UNNAMED_515_CAPACITOR_I138_1")
		)
		(pad "2" smd rect
			(at 0.264922 0 180)
			(size 0.3048 0.381)
			(layers "F.Cu" "F.Mask" "F.Paste")
			(net "SG")
		)
		(zone
			(layer "F.Cu")
			(hatch none 0.5)
			(connect_pads
				(clearance 0)
			)
			(min_thickness 0.25)
			(keepout
				(tracks allowed)
				(vias not_allowed)
				(pads allowed)
				(copperpour not_allowed)
				(footprints allowed)
			)
			(placement
				(enabled no)
				(sheetname "")
			)
			(fill
				(thermal_gap 0.5)
				(thermal_bridge_width 0.5)
				(island_removal_mode 0)
			)
			(polygon
				(pts
					(xy 138.542522 -15.9385) (xy 138.542522 -16.3195) (xy 138.317478 -16.3195) (xy 138.317478 -15.9385)
				)
			)
		)
	)
	(footprint ""
		(layer "F.Cu")
		(at 99.06 -59.055 90)
		(property "Reference" "TP78"
			(at -2.9464 -0.47625 90)
			(unlocked yes)
			(layer "F.SilkS")
			(effects
				(font
					(size 0.635 0.4064)
					(thickness 0.1524)
				)
				(justify left)
			)
		)
		(property "Value" ""
			(at 0 0 90)
			(layer "F.Fab")
			(effects
				(font
					(size 1.27 1.27)
				)
			)
		)
		(property "Device Type" "TP_PIONT-TP010CT020B030_PTH-TPA"
			(at -1.341882 0.996696 90)
			(unlocked yes)
			(layer "F.Fab")
			(hide yes)
			(effects
				(font
					(size 0.7874 0.5842)
					(thickness 0.1524)
				)
				(justify left)
			)
		)
		(duplicate_pad_numbers_are_jumpers no)
		(fp_poly
			(pts
				(arc
					(start 0 0.889)
					(mid 0 -0.889)
					(end 0 0.889)
				)
			)
			(stroke
				(width 0)
				(type default)
			)
			(fill no)
			(layer "B.CrtYd")
		)
		(fp_poly
			(pts
				(arc
					(start 0 0.889)
					(mid 0 -0.889)
					(end 0 0.889)
				)
			)
			(stroke
				(width 0)
				(type default)
			)
			(fill no)
			(layer "F.CrtYd")
		)
		(pad "1" thru_hole circle
			(at 0 0 90)
			(size 0.508 0.508)
			(drill 0.254)
			(layers "*.Cu" "*.Mask")
			(remove_unused_layers no)
			(net "IO_L20P_16")
			(clearance 0.1016)
			(padstack
				(mode front_inner_back)
				(layer "Inner"
					(shape circle)
					(size 0.508 0.508)
					(clearance 0.1016)
				)
				(layer "B.Cu"
					(shape circle)
					(size 0.762 0.762)
					(clearance -0.0254)
				)
			)
		)
	)
	(footprint ""
		(layer "F.Cu")
		(at 39.37 -128.905)
		(property "Reference" "SP35"
			(at 0 0 0)
			(layer "F.SilkS")
			(hide yes)
			(effects
				(font
					(size 1.27 1.27)
				)
			)
		)
		(property "Value" ""
			(at 0 0 0)
			(layer "F.Fab")
			(effects
				(font
					(size 1.27 1.27)
				)
			)
		)
		(duplicate_pad_numbers_are_jumpers no)
	)
	(footprint ""
		(layer "F.Cu")
		(at 105.41 -64.2874 -90)
		(property "Reference" "R327"
			(at 0.0254 -2.70637 90)
			(unlocked yes)
			(layer "F.SilkS")
			(effects
				(font
					(size 0.7874 0.5842)
					(thickness 0.1524)
				)
			)
		)
		(property "Value" "VAL*"
			(at 0.02032 2.13233 270)
			(unlocked yes)
			(layer "F.Fab")
			(hide yes)
			(effects
				(font
					(size 0.7874 0.5842)
					(thickness 0.1524)
				)
			)
		)
		(property "Tolerance" "TOL*"
			(at 0.044704 3.05435 270)
			(unlocked yes)
			(layer "Cmts.User")
			(hide yes)
			(effects
				(font
					(size 0.7874 0.5842)
					(thickness 0.1524)
				)
			)
		)
		(property "User Part Number" "PARTNUM*"
			(at 0.02032 4.024884 270)
			(unlocked yes)
			(layer "Cmts.User")
			(hide yes)
			(effects
				(font
					(size 0.7874 0.5842)
					(thickness 0.1524)
				)
			)
		)
		(property "Device Type" "RESISTOR-G155-11002-01,10KOHM,A"
			(at 0.008382 1.210564 270)
			(unlocked yes)
			(layer "F.Fab")
			(hide yes)
			(effects
				(font
					(size 0.7874 0.5842)
					(thickness 0.1524)
				)
			)
		)
		(duplicate_pad_numbers_are_jumpers no)
		(fp_line
			(start -1.143 0.5588)
			(end 1.143 0.5588)
			(stroke
				(width 0.1)
				(type default)
			)
			(layer "F.SilkS")
		)
		(fp_line
			(start 1.143 0.5588)
			(end 1.143 -0.5588)
			(stroke
				(width 0.1)
				(type default)
			)
			(layer "F.SilkS")
		)
		(fp_line
			(start -1.143 -0.5588)
			(end -1.143 0.5588)
			(stroke
				(width 0.1)
				(type default)
			)
			(layer "F.SilkS")
		)
		(fp_line
			(start 1.143 -0.5588)
			(end -1.143 -0.5588)
			(stroke
				(width 0.1)
				(type default)
			)
			(layer "F.SilkS")
		)
		(fp_poly
			(pts
				(xy -1.143 0.5588) (xy 1.143 0.5588) (xy 1.143 -0.5588) (xy -1.143 -0.5588)
			)
			(stroke
				(width 0)
				(type default)
			)
			(fill no)
			(layer "F.CrtYd")
		)
		(fp_line
			(start -0.508 0.3048)
			(end 0.508 0.3048)
			(stroke
				(width 0.1)
				(type default)
			)
			(layer "F.Fab")
		)
		(fp_line
			(start 0.508 0.3048)
			(end 0.508 -0.3048)
			(stroke
				(width 0.1)
				(type default)
			)
			(layer "F.Fab")
		)
		(fp_line
			(start -0.508 -0.3048)
			(end -0.508 0.3048)
			(stroke
				(width 0.1)
				(type default)
			)
			(layer "F.Fab")
		)
		(fp_line
			(start 0.508 -0.3048)
			(end -0.508 -0.3048)
			(stroke
				(width 0.1)
				(type default)
			)
			(layer "F.Fab")
		)
		(pad "1" smd rect
			(at -0.5334 0 270)
			(size 0.7112 0.6096)
			(layers "F.Cu" "F.Mask" "F.Paste")
			(net "XP3R3V_FPGA")
		)
		(pad "2" smd rect
			(at 0.5334 0 270)
			(size 0.7112 0.6096)
			(layers "F.Cu" "F.Mask" "F.Paste")
			(net "FPGA_IO_7")
		)
		(zone
			(layer "F.Cu")
			(hatch none 0.5)
			(connect_pads
				(clearance 0)
			)
			(min_thickness 0.25)
			(keepout
				(tracks not_allowed)
				(vias allowed)
				(pads allowed)
				(copperpour not_allowed)
				(footprints allowed)
			)
			(placement
				(enabled no)
				(sheetname "")
			)
			(fill
				(thermal_gap 0.5)
				(thermal_bridge_width 0.5)
				(island_removal_mode 0)
			)
			(polygon
				(pts
					(xy 105.1052 -64.3636) (xy 105.1052 -64.2112) (xy 105.7148 -64.2112) (xy 105.7148 -64.3636)
				)
			)
		)
		(zone
			(layer "F.Cu")
			(hatch none 0.5)
			(connect_pads
				(clearance 0)
			)
			(min_thickness 0.25)
			(keepout
				(tracks allowed)
				(vias not_allowed)
				(pads allowed)
				(copperpour not_allowed)
				(footprints allowed)
			)
			(placement
				(enabled no)
				(sheetname "")
			)
			(fill
				(thermal_gap 0.5)
				(thermal_bridge_width 0.5)
				(island_removal_mode 0)
			)
			(polygon
				(pts
					(xy 105.1052 -64.3636) (xy 105.1052 -64.2112) (xy 105.7148 -64.2112) (xy 105.7148 -64.3636)
				)
			)
		)
	)
	(footprint ""
		(layer "F.Cu")
		(at 12.8524 -55.0164 180)
		(property "Reference" "C318"
			(at 2.1844 -0.19177 0)
			(unlocked yes)
			(layer "F.SilkS")
			(effects
				(font
					(size 0.7874 0.5842)
					(thickness 0.1524)
				)
			)
		)
		(property "Value" "VAL*"
			(at 0.193548 2.13614 180)
			(unlocked yes)
			(layer "F.Fab")
			(hide yes)
			(effects
				(font
					(size 0.7874 0.5842)
					(thickness 0.1524)
				)
			)
		)
		(property "User Part Number" "PARTNUM*"
			(at 0.216154 4.185666 180)
			(unlocked yes)
			(layer "Cmts.User")
			(hide yes)
			(effects
				(font
					(size 0.7874 0.5842)
					(thickness 0.1524)
				)
			)
		)
		(property "Device Type" "CAPACITOR-G104-0A180-FJ,18PF,5%"
			(at 0.184404 1.180592 180)
			(unlocked yes)
			(layer "F.Fab")
			(hide yes)
			(effects
				(font
					(size 0.7874 0.5842)
					(thickness 0.1524)
				)
			)
		)
		(property "Tolerance" "TOL*"
			(at 0.216154 3.1496 180)
			(unlocked yes)
			(layer "Cmts.User")
			(hide yes)
			(effects
				(font
					(size 0.7874 0.5842)
					(thickness 0.1524)
				)
			)
		)
		(duplicate_pad_numbers_are_jumpers no)
		(fp_line
			(start 0.671322 0.4445)
			(end -0.671322 0.4445)
			(stroke
				(width 0.1)
				(type default)
			)
			(layer "F.SilkS")
		)
		(fp_line
			(start 0.671322 -0.4445)
			(end 0.671322 0.4445)
			(stroke
				(width 0.1)
				(type default)
			)
			(layer "F.SilkS")
		)
		(fp_line
			(start -0.671322 0.4445)
			(end -0.671322 -0.4445)
			(stroke
				(width 0.1)
				(type default)
			)
			(layer "F.SilkS")
		)
		(fp_line
			(start -0.671322 -0.4445)
			(end 0.671322 -0.4445)
			(stroke
				(width 0.1)
				(type default)
			)
			(layer "F.SilkS")
		)
		(fp_rect
			(start -0.671322 0.4445)
			(end 0.671322 -0.4445)
			(stroke
				(width 0)
				(type default)
			)
			(fill no)
			(layer "F.CrtYd")
		)
		(fp_line
			(start 0.31496 0.1651)
			(end 0.31496 -0.1651)
			(stroke
				(width 0.1)
				(type default)
			)
			(layer "F.Fab")
		)
		(fp_line
			(start 0.31496 -0.1651)
			(end -0.31496 -0.1651)
			(stroke
				(width 0.1)
				(type default)
			)
			(layer "F.Fab")
		)
		(fp_line
			(start -0.31496 0.1651)
			(end 0.31496 0.1651)
			(stroke
				(width 0.1)
				(type default)
			)
			(layer "F.Fab")
		)
		(fp_line
			(start -0.31496 -0.1651)
			(end -0.31496 0.1651)
			(stroke
				(width 0.1)
				(type default)
			)
			(layer "F.Fab")
		)
		(pad "1" smd rect
			(at -0.264922 0 180)
			(size 0.3048 0.381)
			(layers "F.Cu" "F.Mask" "F.Paste")
			(net "SG")
		)
		(pad "2" smd rect
			(at 0.264922 0 180)
			(size 0.3048 0.381)
			(layers "F.Cu" "F.Mask" "F.Paste")
			(net "UNNAMED_12_CAPACITOR_I332_2")
		)
		(zone
			(layer "F.Cu")
			(hatch none 0.5)
			(connect_pads
				(clearance 0)
			)
			(min_thickness 0.25)
			(keepout
				(tracks not_allowed)
				(vias allowed)
				(pads allowed)
				(copperpour not_allowed)
				(footprints allowed)
			)
			(placement
				(enabled no)
				(sheetname "")
			)
			(fill
				(thermal_gap 0.5)
				(thermal_bridge_width 0.5)
				(island_removal_mode 0)
			)
			(polygon
				(pts
					(xy 12.964922 -55.2069) (xy 12.739878 -55.2069) (xy 12.739878 -54.8259) (xy 12.964922 -54.8259)
				)
			)
		)
		(zone
			(layer "F.Cu")
			(hatch none 0.5)
			(connect_pads
				(clearance 0)
			)
			(min_thickness 0.25)
			(keepout
				(tracks allowed)
				(vias not_allowed)
				(pads allowed)
				(copperpour not_allowed)
				(footprints allowed)
			)
			(placement
				(enabled no)
				(sheetname "")
			)
			(fill
				(thermal_gap 0.5)
				(thermal_bridge_width 0.5)
				(island_removal_mode 0)
			)
			(polygon
				(pts
					(xy 12.964922 -54.8259) (xy 12.964922 -55.2069) (xy 12.739878 -55.2069) (xy 12.739878 -54.8259)
				)
			)
		)
	)
	(footprint ""
		(layer "F.Cu")
		(at 94.7928 -75.819 -90)
		(property "Reference" "C185"
			(at -19.304 27.57043 90)
			(unlocked yes)
			(layer "F.SilkS")
			(effects
				(font
					(size 0.7874 0.5842)
					(thickness 0.1524)
				)
			)
		)
		(property "Value" "VAL*"
			(at 0.0762 3.134106 270)
			(unlocked yes)
			(layer "F.Fab")
			(hide yes)
			(effects
				(font
					(size 0.7874 0.5842)
					(thickness 0.1524)
				)
			)
		)
		(property "Device Type" "CAPACITOR-G107-0F106-EM,10UF,2A"
			(at 0.0508 2.194306 270)
			(unlocked yes)
			(layer "F.Fab")
			(hide yes)
			(effects
				(font
					(size 0.7874 0.5842)
					(thickness 0.1524)
				)
			)
		)
		(property "User Part Number" "PARTNUM*"
			(at 0.1016 5.013706 270)
			(unlocked yes)
			(layer "Cmts.User")
			(hide yes)
			(effects
				(font
					(size 0.7874 0.5842)
					(thickness 0.1524)
				)
			)
		)
		(property "Tolerance" "TOL*"
			(at 0.0762 4.048506 270)
			(unlocked yes)
			(layer "Cmts.User")
			(hide yes)
			(effects
				(font
					(size 0.7874 0.5842)
					(thickness 0.1524)
				)
			)
		)
		(duplicate_pad_numbers_are_jumpers no)
		(fp_line
			(start -1.5748 0.9398)
			(end 1.5748 0.9398)
			(stroke
				(width 0.1)
				(type default)
			)
			(layer "F.SilkS")
		)
		(fp_line
			(start 1.5748 0.9398)
			(end 1.5748 -0.9398)
			(stroke
				(width 0.1)
				(type default)
			)
			(layer "F.SilkS")
		)
		(fp_line
			(start -1.5748 -0.9398)
			(end -1.5748 0.9398)
			(stroke
				(width 0.1)
				(type default)
			)
			(layer "F.SilkS")
		)
		(fp_line
			(start 1.5748 -0.9398)
			(end -1.5748 -0.9398)
			(stroke
				(width 0.1)
				(type default)
			)
			(layer "F.SilkS")
		)
		(fp_rect
			(start -1.5748 0.9398)
			(end 1.5748 -0.9398)
			(stroke
				(width 0)
				(type default)
			)
			(fill no)
			(layer "F.CrtYd")
		)
		(fp_line
			(start -1.016 0.635)
			(end 1.016 0.635)
			(stroke
				(width 0.1)
				(type default)
			)
			(layer "F.Fab")
		)
		(fp_line
			(start 1.016 0.635)
			(end 1.016 -0.635)
			(stroke
				(width 0.1)
				(type default)
			)
			(layer "F.Fab")
		)
		(fp_line
			(start -1.016 -0.635)
			(end -1.016 0.635)
			(stroke
				(width 0.1)
				(type default)
			)
			(layer "F.Fab")
		)
		(fp_line
			(start 1.016 -0.635)
			(end -1.016 -0.635)
			(stroke
				(width 0.1)
				(type default)
			)
			(layer "F.Fab")
		)
		(pad "1" smd rect
			(at -0.8382 0 270)
			(size 0.9652 1.3716)
			(layers "F.Cu" "F.Mask" "F.Paste")
			(net "XP1R2V_VIN")
		)
		(pad "2" smd rect
			(at 0.8382 0 270)
			(size 0.9652 1.3716)
			(layers "F.Cu" "F.Mask" "F.Paste")
			(net "SG")
		)
		(zone
			(layer "F.Cu")
			(hatch none 0.5)
			(connect_pads
				(clearance 0)
			)
			(min_thickness 0.25)
			(keepout
				(tracks allowed)
				(vias not_allowed)
				(pads allowed)
				(copperpour not_allowed)
				(footprints allowed)
			)
			(placement
				(enabled no)
				(sheetname "")
			)
			(fill
				(thermal_gap 0.5)
				(thermal_bridge_width 0.5)
				(island_removal_mode 0)
			)
			(polygon
				(pts
					(xy 94.1578 -76.0476) (xy 94.1578 -75.5904) (xy 95.4278 -75.5904) (xy 95.4278 -76.0476)
				)
			)
		)
	)
	(footprint ""
		(layer "F.Cu")
		(at 151.613108 -49.01311 90)
		(property "Reference" "R68"
			(at 0.00127 -2.882138 90)
			(unlocked yes)
			(layer "F.SilkS")
			(effects
				(font
					(size 0.7874 0.5842)
					(thickness 0.1524)
				)
			)
		)
		(property "Value" "VAL*"
			(at 0.02032 2.13233 90)
			(unlocked yes)
			(layer "F.Fab")
			(hide yes)
			(effects
				(font
					(size 0.7874 0.5842)
					(thickness 0.1524)
				)
			)
		)
		(property "Device Type" "RESISTOR-G155-14701-01,4.7KOHMA"
			(at 0.008382 1.210564 90)
			(unlocked yes)
			(layer "F.Fab")
			(hide yes)
			(effects
				(font
					(size 0.7874 0.5842)
					(thickness 0.1524)
				)
			)
		)
		(property "User Part Number" "PARTNUM*"
			(at 0.02032 4.024884 90)
			(unlocked yes)
			(layer "Cmts.User")
			(hide yes)
			(effects
				(font
					(size 0.7874 0.5842)
					(thickness 0.1524)
				)
			)
		)
		(property "Tolerance" "TOL*"
			(at 0.044704 3.05435 90)
			(unlocked yes)
			(layer "Cmts.User")
			(hide yes)
			(effects
				(font
					(size 0.7874 0.5842)
					(thickness 0.1524)
				)
			)
		)
		(duplicate_pad_numbers_are_jumpers no)
		(fp_line
			(start 1.143 -0.5588)
			(end -1.143 -0.5588)
			(stroke
				(width 0.1)
				(type default)
			)
			(layer "F.SilkS")
		)
		(fp_line
			(start -1.143 -0.5588)
			(end -1.143 0.5588)
			(stroke
				(width 0.1)
				(type default)
			)
			(layer "F.SilkS")
		)
		(fp_line
			(start 1.143 0.5588)
			(end 1.143 -0.5588)
			(stroke
				(width 0.1)
				(type default)
			)
			(layer "F.SilkS")
		)
		(fp_line
			(start -1.143 0.5588)
			(end 1.143 0.5588)
			(stroke
				(width 0.1)
				(type default)
			)
			(layer "F.SilkS")
		)
		(fp_rect
			(start 1.143 0.5588)
			(end -1.143 -0.5588)
			(stroke
				(width 0)
				(type default)
			)
			(fill no)
			(layer "F.CrtYd")
		)
		(fp_line
			(start 0.508 -0.3048)
			(end -0.508 -0.3048)
			(stroke
				(width 0.1)
				(type default)
			)
			(layer "F.Fab")
		)
		(fp_line
			(start -0.508 -0.3048)
			(end -0.508 0.3048)
			(stroke
				(width 0.1)
				(type default)
			)
			(layer "F.Fab")
		)
		(fp_line
			(start 0.508 0.3048)
			(end 0.508 -0.3048)
			(stroke
				(width 0.1)
				(type default)
			)
			(layer "F.Fab")
		)
		(fp_line
			(start -0.508 0.3048)
			(end 0.508 0.3048)
			(stroke
				(width 0.1)
				(type default)
			)
			(layer "F.Fab")
		)
		(pad "1" smd rect
			(at -0.5334 0 90)
			(size 0.7112 0.6096)
			(layers "F.Cu" "F.Mask" "F.Paste")
			(net "XP3R3V_FPGA")
		)
		(pad "2" smd rect
			(at 0.5334 0 90)
			(size 0.7112 0.6096)
			(layers "F.Cu" "F.Mask" "F.Paste")
			(net "SHT3X_ADDR")
		)
		(zone
			(layer "F.Cu")
			(hatch none 0.5)
			(connect_pads
				(clearance 0)
			)
			(min_thickness 0.25)
			(keepout
				(tracks allowed)
				(vias not_allowed)
				(pads allowed)
				(copperpour not_allowed)
				(footprints allowed)
			)
			(placement
				(enabled no)
				(sheetname "")
			)
			(fill
				(thermal_gap 0.5)
				(thermal_bridge_width 0.5)
				(island_removal_mode 0)
			)
			(polygon
				(pts
					(xy 151.917908 -49.08931) (xy 151.308308 -49.08931) (xy 151.308308 -48.93691) (xy 151.917908 -48.93691)
				)
			)
		)
	)
)
